# SCM (Grand Teton) — schematic netlist excerpt (pin names and nets, part order shuffled) for the footprints in the layout excerpt that follows; sources: Cadence DE-HDL packaged netlist, KiCad conversion of 12092022_DA0F0TMDCD0_F0T_Management_Board_D_brd_V3_OCP.brd

R434  Q_RES  33.2 1% CHIP  pkg 0402LF  page 34 : A = SGPIO_CLK_PLD_0 ; B = SGPIO_CLK_0
R110  Q_RES  0 5% CHIP  pkg 0402LF  page 46 : A = RST_BMC_EXTRST_R3_N ; B = RST_BMC_EXTRST_R2_N

(kicad_pcb
	(version 20260206)
	(generator "pcbnew")
	(generator_version "10.0")
	(general
		(thickness 1.6)
		(legacy_teardrops no)
	)
	(paper "A4")
	(title_block
		(title "12092022_DA0F0TMDCD0_F0T_Management_Board_D_brd_V3_OCP.brd")
		(comment 1 "Grand Teton / footprints 563-564 of 1440")
	)
	(layers
		(0 "F.Cu" signal "TOP")
		(4 "In1.Cu" signal "GND")
		(6 "In2.Cu" signal "IN1")
		(8 "In3.Cu" signal "GND1")
		(10 "In4.Cu" signal "IN2")
		(12 "In5.Cu" signal "VCC")
		(14 "In6.Cu" signal "VCC1")
		(16 "In7.Cu" signal "IN3")
		(18 "In8.Cu" signal "GND2")
		(20 "In9.Cu" signal "IN4")
		(22 "In10.Cu" signal "GND3")
		(2 "B.Cu" signal "BOTTOM")
		(9 "F.Adhes" user "F.Adhesive")
		(11 "B.Adhes" user "B.Adhesive")
		(13 "F.Paste" user "Package Geometry/Pastemask Top")
		(15 "B.Paste" user "Package Geometry/Pastemask Bottom")
		(5 "F.SilkS" user "Ref Des/Silkscreen Top")
		(7 "B.SilkS" user "Ref Des/Silkscreen Bottom")
		(1 "F.Mask" user "Board Geometry/Soldermask Top")
		(3 "B.Mask" user "Board Geometry/Soldermask Bottom")
		(17 "Dwgs.User" user "User.Drawings")
		(19 "Cmts.User" user "User.Comments")
		(21 "Eco1.User" user "User.Eco1")
		(23 "Eco2.User" user "User.Eco2")
		(25 "Edge.Cuts" user "Board Geometry/Outline")
		(27 "Margin" user)
		(31 "F.CrtYd" user "Package Geometry/Place Bound Top")
		(29 "B.CrtYd" user "Package Geometry/Place Bound Bottom")
		(35 "F.Fab" user "Ref Des/Assembly Top")
		(33 "B.Fab" user "Ref Des/Assembly Bottom")
	)
	(footprint ""
		(layer "F.Cu")
		(at 84.201 -93.345)
		(property "Reference" "R110"
			(at 0 0 0)
			(layer "F.SilkS")
			(hide yes)
			(effects
				(font
					(size 1.27 1.27)
				)
			)
		)
		(property "Value" ""
			(at 0 0 0)
			(layer "F.Fab")
			(effects
				(font
					(size 1.27 1.27)
				)
			)
		)
		(duplicate_pad_numbers_are_jumpers no)
		(fp_line
			(start -0.7874 -0.4064)
			(end 0.7874 -0.4064)
			(stroke
				(width 0.1524)
				(type default)
			)
			(layer "F.SilkS")
		)
		(fp_line
			(start -0.7874 0.4064)
			(end -0.7874 -0.4064)
			(stroke
				(width 0.1524)
				(type default)
			)
			(layer "F.SilkS")
		)
		(fp_line
			(start 0.7874 -0.4064)
			(end 0.7874 0.4064)
			(stroke
				(width 0.1524)
				(type default)
			)
			(layer "F.SilkS")
		)
		(fp_line
			(start 0.7874 0.4064)
			(end -0.7874 0.4064)
			(stroke
				(width 0.1524)
				(type default)
			)
			(layer "F.SilkS")
		)
		(fp_line
			(start -0.67945 -0.305054)
			(end -0.12065 -0.305054)
			(stroke
				(width 0.1)
				(type default)
			)
			(layer "F.Fab")
		)
		(fp_line
			(start -0.67945 0.3048)
			(end -0.67945 -0.305054)
			(stroke
				(width 0.1)
				(type default)
			)
			(layer "F.Fab")
		)
		(fp_line
			(start -0.12065 -0.305054)
			(end -0.12065 -0.2794)
			(stroke
				(width 0.1)
				(type default)
			)
			(layer "F.Fab")
		)
		(fp_line
			(start -0.12065 -0.2794)
			(end 0.12065 -0.2794)
			(stroke
				(width 0.1)
				(type default)
			)
			(layer "F.Fab")
		)
		(fp_line
			(start -0.12065 0.2794)
			(end -0.12065 0.3048)
			(stroke
				(width 0.1)
				(type default)
			)
			(layer "F.Fab")
		)
		(fp_line
			(start -0.12065 0.3048)
			(end -0.67945 0.3048)
			(stroke
				(width 0.1)
				(type default)
			)
			(layer "F.Fab")
		)
		(fp_line
			(start 0.120396 0.2794)
			(end -0.12065 0.2794)
			(stroke
				(width 0.1)
				(type default)
			)
			(layer "F.Fab")
		)
		(fp_line
			(start 0.120396 0.3048)
			(end 0.120396 0.2794)
			(stroke
				(width 0.1)
				(type default)
			)
			(layer "F.Fab")
		)
		(fp_line
			(start 0.12065 -0.3048)
			(end 0.67945 -0.3048)
			(stroke
				(width 0.1)
				(type default)
			)
			(layer "F.Fab")
		)
		(fp_line
			(start 0.12065 -0.2794)
			(end 0.12065 -0.3048)
			(stroke
				(width 0.1)
				(type default)
			)
			(layer "F.Fab")
		)
		(fp_line
			(start 0.67945 -0.3048)
			(end 0.67945 0.3048)
			(stroke
				(width 0.1)
				(type default)
			)
			(layer "F.Fab")
		)
		(fp_line
			(start 0.67945 0.3048)
			(end 0.120396 0.3048)
			(stroke
				(width 0.1)
				(type default)
			)
			(layer "F.Fab")
		)
		(pad "1" smd circle
			(at -0.40005 0)
			(size 0 0)
			(layers "F.Cu" "F.Mask" "F.Paste")
			(net "RST_BMC_EXTRST_R3_N")
		)
		(pad "2" smd circle
			(at 0.40005 0)
			(size 0 0)
			(layers "F.Cu" "F.Mask" "F.Paste")
			(net "RST_BMC_EXTRST_R2_N")
		)
	)
	(footprint ""
		(layer "F.Cu")
		(at 14.1732 -83.693 90)
		(property "Reference" "R434"
			(at 0 0 90)
			(layer "F.SilkS")
			(hide yes)
			(effects
				(font
					(size 1.27 1.27)
				)
			)
		)
		(property "Value" ""
			(at 0 0 90)
			(layer "F.Fab")
			(effects
				(font
					(size 1.27 1.27)
				)
			)
		)
		(duplicate_pad_numbers_are_jumpers no)
		(fp_line
			(start 0.7874 -0.4064)
			(end 0.7874 0.4064)
			(stroke
				(width 0.1524)
				(type default)
			)
			(layer "F.SilkS")
		)
		(fp_line
			(start -0.7874 -0.4064)
			(end 0.7874 -0.4064)
			(stroke
				(width 0.1524)
				(type default)
			)
			(layer "F.SilkS")
		)
		(fp_line
			(start 0.7874 0.4064)
			(end -0.7874 0.4064)
			(stroke
				(width 0.1524)
				(type default)
			)
			(layer "F.SilkS")
		)
		(fp_line
			(start -0.7874 0.4064)
			(end -0.7874 -0.4064)
			(stroke
				(width 0.1524)
				(type default)
			)
			(layer "F.SilkS")
		)
		(fp_line
			(start -0.12065 -0.305054)
			(end -0.12065 -0.2794)
			(stroke
				(width 0.1)
				(type default)
			)
			(layer "F.Fab")
		)
		(fp_line
			(start -0.67945 -0.305054)
			(end -0.12065 -0.305054)
			(stroke
				(width 0.1)
				(type default)
			)
			(layer "F.Fab")
		)
		(fp_line
			(start 0.67945 -0.3048)
			(end 0.67945 0.3048)
			(stroke
				(width 0.1)
				(type default)
			)
			(layer "F.Fab")
		)
		(fp_line
			(start 0.12065 -0.3048)
			(end 0.67945 -0.3048)
			(stroke
				(width 0.1)
				(type default)
			)
			(layer "F.Fab")
		)
		(fp_line
			(start 0.12065 -0.2794)
			(end 0.12065 -0.3048)
			(stroke
				(width 0.1)
				(type default)
			)
			(layer "F.Fab")
		)
		(fp_line
			(start -0.12065 -0.2794)
			(end 0.12065 -0.2794)
			(stroke
				(width 0.1)
				(type default)
			)
			(layer "F.Fab")
		)
		(fp_line
			(start 0.120396 0.2794)
			(end -0.12065 0.2794)
			(stroke
				(width 0.1)
				(type default)
			)
			(layer "F.Fab")
		)
		(fp_line
			(start -0.12065 0.2794)
			(end -0.12065 0.3048)
			(stroke
				(width 0.1)
				(type default)
			)
			(layer "F.Fab")
		)
		(fp_line
			(start 0.67945 0.3048)
			(end 0.120396 0.3048)
			(stroke
				(width 0.1)
				(type default)
			)
			(layer "F.Fab")
		)
		(fp_line
			(start 0.120396 0.3048)
			(end 0.120396 0.2794)
			(stroke
				(width 0.1)
				(type default)
			)
			(layer "F.Fab")
		)
		(fp_line
			(start -0.12065 0.3048)
			(end -0.67945 0.3048)
			(stroke
				(width 0.1)
				(type default)
			)
			(layer "F.Fab")
		)
		(fp_line
			(start -0.67945 0.3048)
			(end -0.67945 -0.305054)
			(stroke
				(width 0.1)
				(type default)
			)
			(layer "F.Fab")
		)
		(pad "1" smd circle
			(at -0.40005 0 90)
			(size 0 0)
			(layers "F.Cu" "F.Mask" "F.Paste")
			(net "SGPIO_CLK_PLD_0")
		)
		(pad "2" smd circle
			(at 0.40005 0 90)
			(size 0 0)
			(layers "F.Cu" "F.Mask" "F.Paste")
			(net "SGPIO_CLK_0")
		)
	)
)
